(kicad_pcb
	(version 20260206)
	(generator "pcbnew")
	(generator_version "10.0")
	(general
		(thickness 1.6)
		(legacy_teardrops no)
	)
	(paper "A4")
	(title_block
		(title "03242023_DA0F0TMBIJ0_F0T_Motherboard_J_brd_V01_OCP.brd")
		(comment 1 "Grand Teton / footprints 2672-2678 of 6105")
	)
	(layers
		(0 "F.Cu" signal "TOP")
		(4 "In1.Cu" signal "GND")
		(6 "In2.Cu" signal "IN1")
		(8 "In3.Cu" signal "GND1")
		(10 "In4.Cu" signal "IN2")
		(12 "In5.Cu" signal "GND2")
		(14 "In6.Cu" signal "IN3")
		(16 "In7.Cu" signal "GND3")
		(18 "In8.Cu" signal "VCC")
		(20 "In9.Cu" signal "VCC1")
		(22 "In10.Cu" signal "GND4")
		(24 "In11.Cu" signal "IN4")
		(26 "In12.Cu" signal "GND5")
		(28 "In13.Cu" signal "IN5")
		(30 "In14.Cu" signal "GND6")
		(32 "In15.Cu" signal "IN6")
		(34 "In16.Cu" signal "GND7")
		(2 "B.Cu" signal "BOTTOM")
		(9 "F.Adhes" user "F.Adhesive")
		(11 "B.Adhes" user "B.Adhesive")
		(13 "F.Paste" user "Package Geometry/Pastemask Top")
		(15 "B.Paste" user "Package Geometry/Pastemask Bottom")
		(5 "F.SilkS" user "Ref Des/Silkscreen Top")
		(7 "B.SilkS" user "Ref Des/Silkscreen Bottom")
		(1 "F.Mask" user "Board Geometry/Soldermask Top")
		(3 "B.Mask" user "Board Geometry/Soldermask Bottom")
		(17 "Dwgs.User" user "User.Drawings")
		(19 "Cmts.User" user "User.Comments")
		(21 "Eco1.User" user "User.Eco1")
		(23 "Eco2.User" user "User.Eco2")
		(25 "Edge.Cuts" user "Board Geometry/Outline")
		(27 "Margin" user)
		(31 "F.CrtYd" user "Package Geometry/Place Bound Top")
		(29 "B.CrtYd" user "Package Geometry/Place Bound Bottom")
		(35 "F.Fab" user "Ref Des/Assembly Top")
		(33 "B.Fab" user "Ref Des/Assembly Bottom")
	)
	(footprint ""
		(layer "F.Cu")
		(at 417.34613 -402.371052 -90)
		(property "Reference" "C965"
			(at 0 0 270)
			(layer "F.SilkS")
			(hide yes)
			(effects
				(font
					(size 1.27 1.27)
				)
			)
		)
		(property "Value" ""
			(at 0 0 270)
			(layer "F.Fab")
			(effects
				(font
					(size 1.27 1.27)
				)
			)
		)
		(duplicate_pad_numbers_are_jumpers no)
		(fp_line
			(start -0.299974 0.150114)
			(end -0.299974 -0.150114)
			(stroke
				(width 0.1)
				(type default)
			)
			(layer "F.Fab")
		)
		(fp_line
			(start 0.299974 0.150114)
			(end -0.299974 0.150114)
			(stroke
				(width 0.1)
				(type default)
			)
			(layer "F.Fab")
		)
		(fp_line
			(start -0.299974 -0.150114)
			(end 0.299974 -0.150114)
			(stroke
				(width 0.1)
				(type default)
			)
			(layer "F.Fab")
		)
		(fp_line
			(start 0.299974 -0.150114)
			(end 0.299974 0.150114)
			(stroke
				(width 0.1)
				(type default)
			)
			(layer "F.Fab")
		)
		(pad "1" smd rect
			(at -0.2667 0 270)
			(size 0.3048 0.381)
			(layers "F.Cu" "F.Mask" "F.Paste")
			(net "P5E_CPU0_PE2_TX_C_DP<0>")
		)
		(pad "2" smd rect
			(at 0.2667 0 270)
			(size 0.3048 0.381)
			(layers "F.Cu" "F.Mask" "F.Paste")
			(net "P5E_CPU0_PE2_TX_DP<0>")
		)
	)
	(footprint ""
		(layer "F.Cu")
		(at 315.946028 -24.132032 180)
		(property "Reference" "R1403"
			(at 0 0 180)
			(layer "F.SilkS")
			(hide yes)
			(effects
				(font
					(size 1.27 1.27)
				)
			)
		)
		(property "Value" ""
			(at 0 0 180)
			(layer "F.Fab")
			(effects
				(font
					(size 1.27 1.27)
				)
			)
		)
		(duplicate_pad_numbers_are_jumpers no)
		(fp_line
			(start 0.7874 0.4064)
			(end -0.7874 0.4064)
			(stroke
				(width 0.1524)
				(type default)
			)
			(layer "F.SilkS")
		)
		(fp_line
			(start 0.7874 -0.4064)
			(end 0.7874 0.4064)
			(stroke
				(width 0.1524)
				(type default)
			)
			(layer "F.SilkS")
		)
		(fp_line
			(start -0.7874 0.4064)
			(end -0.7874 -0.4064)
			(stroke
				(width 0.1524)
				(type default)
			)
			(layer "F.SilkS")
		)
		(fp_line
			(start -0.7874 -0.4064)
			(end 0.7874 -0.4064)
			(stroke
				(width 0.1524)
				(type default)
			)
			(layer "F.SilkS")
		)
		(fp_line
			(start 0.67945 0.3048)
			(end 0.120396 0.3048)
			(stroke
				(width 0.1)
				(type default)
			)
			(layer "F.Fab")
		)
		(fp_line
			(start 0.67945 -0.3048)
			(end 0.67945 0.3048)
			(stroke
				(width 0.1)
				(type default)
			)
			(layer "F.Fab")
		)
		(fp_line
			(start 0.12065 -0.2794)
			(end 0.12065 -0.3048)
			(stroke
				(width 0.1)
				(type default)
			)
			(layer "F.Fab")
		)
		(fp_line
			(start 0.12065 -0.3048)
			(end 0.67945 -0.3048)
			(stroke
				(width 0.1)
				(type default)
			)
			(layer "F.Fab")
		)
		(fp_line
			(start 0.120396 0.3048)
			(end 0.120396 0.2794)
			(stroke
				(width 0.1)
				(type default)
			)
			(layer "F.Fab")
		)
		(fp_line
			(start 0.120396 0.2794)
			(end -0.12065 0.2794)
			(stroke
				(width 0.1)
				(type default)
			)
			(layer "F.Fab")
		)
		(fp_line
			(start -0.12065 0.3048)
			(end -0.67945 0.3048)
			(stroke
				(width 0.1)
				(type default)
			)
			(layer "F.Fab")
		)
		(fp_line
			(start -0.12065 0.2794)
			(end -0.12065 0.3048)
			(stroke
				(width 0.1)
				(type default)
			)
			(layer "F.Fab")
		)
		(fp_line
			(start -0.12065 -0.2794)
			(end 0.12065 -0.2794)
			(stroke
				(width 0.1)
				(type default)
			)
			(layer "F.Fab")
		)
		(fp_line
			(start -0.12065 -0.305054)
			(end -0.12065 -0.2794)
			(stroke
				(width 0.1)
				(type default)
			)
			(layer "F.Fab")
		)
		(fp_line
			(start -0.67945 0.3048)
			(end -0.67945 -0.305054)
			(stroke
				(width 0.1)
				(type default)
			)
			(layer "F.Fab")
		)
		(fp_line
			(start -0.67945 -0.305054)
			(end -0.12065 -0.305054)
			(stroke
				(width 0.1)
				(type default)
			)
			(layer "F.Fab")
		)
		(pad "1" smd circle
			(at -0.40005 0 180)
			(size 0 0)
			(layers "F.Cu" "F.Mask" "F.Paste")
			(net "PWRGD_PCH_PWROK")
		)
		(pad "2" smd circle
			(at 0.40005 0 180)
			(size 0 0)
			(layers "F.Cu" "F.Mask" "F.Paste")
			(net "GND")
		)
	)
	(footprint ""
		(layer "F.Cu")
		(at 284.39491 -94.42069)
		(property "Reference" "U64"
			(at -1.4986 -3.597148 0)
			(unlocked yes)
			(layer "F.SilkS")
			(effects
				(font
					(size 0.7874 0.5842)
					(thickness 0.1524)
				)
				(justify left)
			)
		)
		(property "Value" ""
			(at 0 0 0)
			(layer "F.Fab")
			(effects
				(font
					(size 1.27 1.27)
				)
			)
		)
		(duplicate_pad_numbers_are_jumpers no)
		(fp_line
			(start -1.8288 -2.500122)
			(end -1.8288 2.500122)
			(stroke
				(width 0.1524)
				(type default)
			)
			(layer "F.SilkS")
		)
		(fp_line
			(start -1.8288 2.500122)
			(end 1.8288 2.500122)
			(stroke
				(width 0.1524)
				(type default)
			)
			(layer "F.SilkS")
		)
		(fp_line
			(start -1.077722 -2.500122)
			(end -1.8288 -2.500122)
			(stroke
				(width 0.1524)
				(type default)
			)
			(layer "F.SilkS")
		)
		(fp_line
			(start 0 -1.4224)
			(end -1.077722 -2.500122)
			(stroke
				(width 0.1524)
				(type default)
			)
			(layer "F.SilkS")
		)
		(fp_line
			(start 1.077722 -2.500122)
			(end 0 -1.4224)
			(stroke
				(width 0.1524)
				(type default)
			)
			(layer "F.SilkS")
		)
		(fp_line
			(start 1.8288 -2.500122)
			(end 1.077722 -2.500122)
			(stroke
				(width 0.1524)
				(type default)
			)
			(layer "F.SilkS")
		)
		(fp_line
			(start 1.8288 2.500122)
			(end 1.8288 -2.500122)
			(stroke
				(width 0.1524)
				(type default)
			)
			(layer "F.SilkS")
		)
		(fp_poly
			(pts
				(xy -2.291588 -3.983228) (xy -2.799588 -2.967228) (xy -3.307588 -3.983228)
			)
			(stroke
				(width 0)
				(type default)
			)
			(fill yes)
			(layer "F.SilkS")
		)
		(fp_line
			(start -1.999996 -2.500122)
			(end -1.999996 2.500122)
			(stroke
				(width 0.1)
				(type default)
			)
			(layer "F.Fab")
		)
		(fp_line
			(start -1.999996 2.500122)
			(end 1.999996 2.500122)
			(stroke
				(width 0.1)
				(type default)
			)
			(layer "F.Fab")
		)
		(fp_line
			(start 1.999996 -2.500122)
			(end -1.999996 -2.500122)
			(stroke
				(width 0.1)
				(type default)
			)
			(layer "F.Fab")
		)
		(fp_line
			(start 1.999996 2.500122)
			(end 1.999996 -2.500122)
			(stroke
				(width 0.1)
				(type default)
			)
			(layer "F.Fab")
		)
		(fp_poly
			(pts
				(xy -4.5085 -2.413) (xy -4.5085 -1.397) (xy -3.4925 -1.905)
			)
			(stroke
				(width 0)
				(type default)
			)
			(fill yes)
			(layer "F.Fab")
		)
		(pad "1" smd rect
			(at -2.599944 -1.905 270)
			(size 0.889 1.27)
			(layers "F.Cu" "F.Mask" "F.Paste")
			(net "MB_FRU_ADDR0")
		)
		(pad "2" smd rect
			(at -2.599944 -0.635 270)
			(size 0.889 1.27)
			(layers "F.Cu" "F.Mask" "F.Paste")
			(net "MB_FRU_ADDR1")
		)
		(pad "3" smd rect
			(at -2.599944 0.635 270)
			(size 0.889 1.27)
			(layers "F.Cu" "F.Mask" "F.Paste")
			(net "MB_FRU_ADDR2")
		)
		(pad "4" smd rect
			(at -2.599944 1.905 270)
			(size 0.889 1.27)
			(layers "F.Cu" "F.Mask" "F.Paste")
			(net "GND")
		)
		(pad "5" smd rect
			(at 2.599944 1.905 270)
			(size 0.889 1.27)
			(layers "F.Cu" "F.Mask" "F.Paste")
			(net "SMB_FRU_3V3AUX_SDA")
		)
		(pad "6" smd rect
			(at 2.599944 0.635 270)
			(size 0.889 1.27)
			(layers "F.Cu" "F.Mask" "F.Paste")
			(net "SMB_FRU_3V3AUX_SCL")
		)
		(pad "7" smd rect
			(at 2.599944 -0.635 270)
			(size 0.889 1.27)
			(layers "F.Cu" "F.Mask" "F.Paste")
			(net "PD_MB_FRU_WP")
		)
		(pad "8" smd rect
			(at 2.599944 -1.905 270)
			(size 0.889 1.27)
			(layers "F.Cu" "F.Mask" "F.Paste")
			(net "P3V3_AUX")
		)
	)
	(footprint ""
		(layer "F.Cu")
		(at 6.43128 -37.252148)
		(property "Reference" ""
			(at 0 0 0)
			(layer "F.SilkS")
			(hide yes)
			(effects
				(font
					(size 1.27 1.27)
				)
			)
		)
		(property "Value" ""
			(at 0 0 0)
			(layer "F.Fab")
			(effects
				(font
					(size 1.27 1.27)
				)
			)
		)
		(duplicate_pad_numbers_are_jumpers no)
		(pad "1" smd circle
			(at 0 0)
			(size 0.9906 0.9906)
			(layers "F.Cu" "F.Mask" "F.Paste")
			(net "Net_8482")
		)
		(zone
			(layer "F.Cu")
			(hatch none 0.5)
			(connect_pads
				(clearance 0)
			)
			(min_thickness 0.25)
			(keepout
				(tracks not_allowed)
				(vias allowed)
				(pads allowed)
				(copperpour not_allowed)
				(footprints allowed)
			)
			(placement
				(enabled no)
				(sheetname "")
			)
			(fill
				(thermal_gap 0.5)
				(thermal_bridge_width 0.5)
				(island_removal_mode 0)
			)
			(polygon
				(pts
					(arc
						(start 8.05688 -37.252148)
						(mid 4.80568 -37.252148)
						(end 8.05688 -37.252148)
					)
				)
			)
		)
	)
	(footprint ""
		(layer "F.Cu")
		(at 454.662794 -384.301492 -90)
		(property "Reference" "PC1846"
			(at 0 0 270)
			(layer "F.SilkS")
			(hide yes)
			(effects
				(font
					(size 1.27 1.27)
				)
			)
		)
		(property "Value" ""
			(at 0 0 270)
			(layer "F.Fab")
			(effects
				(font
					(size 1.27 1.27)
				)
			)
		)
		(duplicate_pad_numbers_are_jumpers no)
		(fp_line
			(start -0.7874 0.4064)
			(end -0.7874 -0.4064)
			(stroke
				(width 0.1524)
				(type default)
			)
			(layer "F.SilkS")
		)
		(fp_line
			(start 0.7874 0.4064)
			(end -0.7874 0.4064)
			(stroke
				(width 0.1524)
				(type default)
			)
			(layer "F.SilkS")
		)
		(fp_line
			(start -0.7874 -0.4064)
			(end 0.7874 -0.4064)
			(stroke
				(width 0.1524)
				(type default)
			)
			(layer "F.SilkS")
		)
		(fp_line
			(start 0.7874 -0.4064)
			(end 0.7874 0.4064)
			(stroke
				(width 0.1524)
				(type default)
			)
			(layer "F.SilkS")
		)
		(fp_line
			(start -0.67945 0.3048)
			(end -0.67945 -0.305054)
			(stroke
				(width 0.1)
				(type default)
			)
			(layer "F.Fab")
		)
		(fp_line
			(start -0.12065 0.3048)
			(end -0.67945 0.3048)
			(stroke
				(width 0.1)
				(type default)
			)
			(layer "F.Fab")
		)
		(fp_line
			(start 0.120396 0.3048)
			(end 0.120396 0.2794)
			(stroke
				(width 0.1)
				(type default)
			)
			(layer "F.Fab")
		)
		(fp_line
			(start 0.67945 0.3048)
			(end 0.120396 0.3048)
			(stroke
				(width 0.1)
				(type default)
			)
			(layer "F.Fab")
		)
		(fp_line
			(start -0.12065 0.2794)
			(end -0.12065 0.3048)
			(stroke
				(width 0.1)
				(type default)
			)
			(layer "F.Fab")
		)
		(fp_line
			(start 0.120396 0.2794)
			(end -0.12065 0.2794)
			(stroke
				(width 0.1)
				(type default)
			)
			(layer "F.Fab")
		)
		(fp_line
			(start -0.12065 -0.2794)
			(end 0.12065 -0.2794)
			(stroke
				(width 0.1)
				(type default)
			)
			(layer "F.Fab")
		)
		(fp_line
			(start 0.12065 -0.2794)
			(end 0.12065 -0.3048)
			(stroke
				(width 0.1)
				(type default)
			)
			(layer "F.Fab")
		)
		(fp_line
			(start 0.12065 -0.3048)
			(end 0.67945 -0.3048)
			(stroke
				(width 0.1)
				(type default)
			)
			(layer "F.Fab")
		)
		(fp_line
			(start 0.67945 -0.3048)
			(end 0.67945 0.3048)
			(stroke
				(width 0.1)
				(type default)
			)
			(layer "F.Fab")
		)
		(fp_line
			(start -0.67945 -0.305054)
			(end -0.12065 -0.305054)
			(stroke
				(width 0.1)
				(type default)
			)
			(layer "F.Fab")
		)
		(fp_line
			(start -0.12065 -0.305054)
			(end -0.12065 -0.2794)
			(stroke
				(width 0.1)
				(type default)
			)
			(layer "F.Fab")
		)
		(pad "1" smd circle
			(at -0.40005 0 270)
			(size 0 0)
			(layers "F.Cu" "F.Mask" "F.Paste")
			(net "SW_P5V_AUX_FLT")
		)
		(pad "2" smd circle
			(at 0.40005 0 270)
			(size 0 0)
			(layers "F.Cu" "F.Mask" "F.Paste")
			(net "GND")
		)
	)
	(footprint ""
		(layer "F.Cu")
		(at 177.9524 -94.338648 90)
		(property "Reference" "R4585"
			(at 0 0 90)
			(layer "F.SilkS")
			(hide yes)
			(effects
				(font
					(size 1.27 1.27)
				)
			)
		)
		(property "Value" ""
			(at 0 0 90)
			(layer "F.Fab")
			(effects
				(font
					(size 1.27 1.27)
				)
			)
		)
		(duplicate_pad_numbers_are_jumpers no)
		(fp_line
			(start 0.7874 -0.4064)
			(end 0.7874 0.4064)
			(stroke
				(width 0.1524)
				(type default)
			)
			(layer "F.SilkS")
		)
		(fp_line
			(start -0.7874 -0.4064)
			(end 0.7874 -0.4064)
			(stroke
				(width 0.1524)
				(type default)
			)
			(layer "F.SilkS")
		)
		(fp_line
			(start 0.7874 0.4064)
			(end -0.7874 0.4064)
			(stroke
				(width 0.1524)
				(type default)
			)
			(layer "F.SilkS")
		)
		(fp_line
			(start -0.7874 0.4064)
			(end -0.7874 -0.4064)
			(stroke
				(width 0.1524)
				(type default)
			)
			(layer "F.SilkS")
		)
		(fp_line
			(start -0.12065 -0.305054)
			(end -0.12065 -0.2794)
			(stroke
				(width 0.1)
				(type default)
			)
			(layer "F.Fab")
		)
		(fp_line
			(start -0.67945 -0.305054)
			(end -0.12065 -0.305054)
			(stroke
				(width 0.1)
				(type default)
			)
			(layer "F.Fab")
		)
		(fp_line
			(start 0.67945 -0.3048)
			(end 0.67945 0.3048)
			(stroke
				(width 0.1)
				(type default)
			)
			(layer "F.Fab")
		)
		(fp_line
			(start 0.12065 -0.3048)
			(end 0.67945 -0.3048)
			(stroke
				(width 0.1)
				(type default)
			)
			(layer "F.Fab")
		)
		(fp_line
			(start 0.12065 -0.2794)
			(end 0.12065 -0.3048)
			(stroke
				(width 0.1)
				(type default)
			)
			(layer "F.Fab")
		)
		(fp_line
			(start -0.12065 -0.2794)
			(end 0.12065 -0.2794)
			(stroke
				(width 0.1)
				(type default)
			)
			(layer "F.Fab")
		)
		(fp_line
			(start 0.120396 0.2794)
			(end -0.12065 0.2794)
			(stroke
				(width 0.1)
				(type default)
			)
			(layer "F.Fab")
		)
		(fp_line
			(start -0.12065 0.2794)
			(end -0.12065 0.3048)
			(stroke
				(width 0.1)
				(type default)
			)
			(layer "F.Fab")
		)
		(fp_line
			(start 0.67945 0.3048)
			(end 0.120396 0.3048)
			(stroke
				(width 0.1)
				(type default)
			)
			(layer "F.Fab")
		)
		(fp_line
			(start 0.120396 0.3048)
			(end 0.120396 0.2794)
			(stroke
				(width 0.1)
				(type default)
			)
			(layer "F.Fab")
		)
		(fp_line
			(start -0.12065 0.3048)
			(end -0.67945 0.3048)
			(stroke
				(width 0.1)
				(type default)
			)
			(layer "F.Fab")
		)
		(fp_line
			(start -0.67945 0.3048)
			(end -0.67945 -0.305054)
			(stroke
				(width 0.1)
				(type default)
			)
			(layer "F.Fab")
		)
		(pad "1" smd rect
			(at -0.40005 0 270)
			(size 0.4572 0.508)
			(layers "F.Cu" "F.Mask" "F.Paste")
			(net "FM_BOARD_BMC_SKU_ID0")
		)
		(pad "2" smd rect
			(at 0.40005 0 270)
			(size 0.4572 0.508)
			(layers "F.Cu" "F.Mask" "F.Paste")
			(net "GND")
		)
	)
	(footprint ""
		(layer "F.Cu")
		(at 193.93408 -351.551748 180)
		(property "Reference" "R625"
			(at 0 0 180)
			(layer "F.SilkS")
			(hide yes)
			(effects
				(font
					(size 1.27 1.27)
				)
			)
		)
		(property "Value" ""
			(at 0 0 180)
			(layer "F.Fab")
			(effects
				(font
					(size 1.27 1.27)
				)
			)
		)
		(duplicate_pad_numbers_are_jumpers no)
		(fp_line
			(start 0.7874 0.4064)
			(end -0.7874 0.4064)
			(stroke
				(width 0.1524)
				(type default)
			)
			(layer "F.SilkS")
		)
		(fp_line
			(start 0.7874 -0.4064)
			(end 0.7874 0.4064)
			(stroke
				(width 0.1524)
				(type default)
			)
			(layer "F.SilkS")
		)
		(fp_line
			(start -0.7874 0.4064)
			(end -0.7874 -0.4064)
			(stroke
				(width 0.1524)
				(type default)
			)
			(layer "F.SilkS")
		)
		(fp_line
			(start -0.7874 -0.4064)
			(end 0.7874 -0.4064)
			(stroke
				(width 0.1524)
				(type default)
			)
			(layer "F.SilkS")
		)
		(fp_line
			(start 0.67945 0.3048)
			(end 0.120396 0.3048)
			(stroke
				(width 0.1)
				(type default)
			)
			(layer "F.Fab")
		)
		(fp_line
			(start 0.67945 -0.3048)
			(end 0.67945 0.3048)
			(stroke
				(width 0.1)
				(type default)
			)
			(layer "F.Fab")
		)
		(fp_line
			(start 0.12065 -0.2794)
			(end 0.12065 -0.3048)
			(stroke
				(width 0.1)
				(type default)
			)
			(layer "F.Fab")
		)
		(fp_line
			(start 0.12065 -0.3048)
			(end 0.67945 -0.3048)
			(stroke
				(width 0.1)
				(type default)
			)
			(layer "F.Fab")
		)
		(fp_line
			(start 0.120396 0.3048)
			(end 0.120396 0.2794)
			(stroke
				(width 0.1)
				(type default)
			)
			(layer "F.Fab")
		)
		(fp_line
			(start 0.120396 0.2794)
			(end -0.12065 0.2794)
			(stroke
				(width 0.1)
				(type default)
			)
			(layer "F.Fab")
		)
		(fp_line
			(start -0.12065 0.3048)
			(end -0.67945 0.3048)
			(stroke
				(width 0.1)
				(type default)
			)
			(layer "F.Fab")
		)
		(fp_line
			(start -0.12065 0.2794)
			(end -0.12065 0.3048)
			(stroke
				(width 0.1)
				(type default)
			)
			(layer "F.Fab")
		)
		(fp_line
			(start -0.12065 -0.2794)
			(end 0.12065 -0.2794)
			(stroke
				(width 0.1)
				(type default)
			)
			(layer "F.Fab")
		)
		(fp_line
			(start -0.12065 -0.305054)
			(end -0.12065 -0.2794)
			(stroke
				(width 0.1)
				(type default)
			)
			(layer "F.Fab")
		)
		(fp_line
			(start -0.67945 0.3048)
			(end -0.67945 -0.305054)
			(stroke
				(width 0.1)
				(type default)
			)
			(layer "F.Fab")
		)
		(fp_line
			(start -0.67945 -0.305054)
			(end -0.12065 -0.305054)
			(stroke
				(width 0.1)
				(type default)
			)
			(layer "F.Fab")
		)
		(pad "1" smd circle
			(at -0.40005 0 180)
			(size 0 0)
			(layers "F.Cu" "F.Mask" "F.Paste")
			(net "P3V3_AUX")
		)
		(pad "2" smd circle
			(at 0.40005 0 180)
			(size 0 0)
			(layers "F.Cu" "F.Mask" "F.Paste")
			(net "PD_PIROM_CPU1_ADDR2")
		)
	)
)
